# BASEBOARD_FAB2 (Tioga Pass) — schematic netlist excerpt (pin names and nets, part order shuffled) for the footprints in the layout excerpt that follows; sources: Cadence DE-HDL packaged netlist, KiCad conversion of Wiwynn_Tioga_Pass_MB.brd

R7C3  RES  51.1 1.0% CHIP  pkg 0402  page 212 : A = PVCCIO_CPU0 ; B = GND
C4F4  CAPP  68UF 16V 20% TANT  pkg 3018  page 195 : A = P12V_STBY ; B = GND
C4A12  CAP  1000PF 50V 10% X7R  pkg 0402LF  page 222 : A = PWRGD_PVTT_DEF_CPU0_R ; B = GND

(kicad_pcb
	(version 20260206)
	(generator "pcbnew")
	(generator_version "10.0")
	(general
		(thickness 1.6)
		(legacy_teardrops no)
	)
	(paper "A4")
	(title_block
		(title "Wiwynn_Tioga_Pass_MB.brd")
		(comment 1 "Tioga Pass / footprints 800-802 of 4770")
	)
	(layers
		(0 "F.Cu" signal "TOP")
		(4 "In1.Cu" signal "L2GND")
		(6 "In2.Cu" signal "L3")
		(8 "In3.Cu" signal "L4GND")
		(10 "In4.Cu" signal "L5")
		(12 "In5.Cu" signal "L6GND")
		(14 "In6.Cu" signal "L7VCC")
		(16 "In7.Cu" signal "L8VCC")
		(18 "In8.Cu" signal "L9GND")
		(20 "In9.Cu" signal "L10")
		(22 "In10.Cu" signal "L11GND")
		(24 "In11.Cu" signal "L12")
		(26 "In12.Cu" signal "L13GND")
		(2 "B.Cu" signal "BOTTOM")
		(9 "F.Adhes" user "F.Adhesive")
		(11 "B.Adhes" user "B.Adhesive")
		(13 "F.Paste" user "Package Geometry/Pastemask Top")
		(15 "B.Paste" user "Package Geometry/Pastemask Bottom")
		(5 "F.SilkS" user "Ref Des/Silkscreen Top")
		(7 "B.SilkS" user "Ref Des/Silkscreen Bottom")
		(1 "F.Mask" user "Board Geometry/Soldermask Top")
		(3 "B.Mask" user "Board Geometry/Soldermask Bottom")
		(17 "Dwgs.User" user "User.Drawings")
		(19 "Cmts.User" user "User.Comments")
		(21 "Eco1.User" user "User.Eco1")
		(23 "Eco2.User" user "User.Eco2")
		(25 "Edge.Cuts" user "Board Geometry/Outline")
		(27 "Margin" user)
		(31 "F.CrtYd" user "Package Geometry/Place Bound Top")
		(29 "B.CrtYd" user "Package Geometry/Place Bound Bottom")
		(35 "F.Fab" user "Ref Des/Assembly Top")
		(33 "B.Fab" user "Ref Des/Assembly Bottom")
	)
	(footprint ""
		(layer "F.Cu")
		(at 339.6742 -105.029 90)
		(property "Reference" "R7C3"
			(at 0 0 90)
			(layer "F.SilkS")
			(hide yes)
			(effects
				(font
					(size 1.27 1.27)
				)
			)
		)
		(property "Value" ""
			(at 0 0 90)
			(layer "F.Fab")
			(effects
				(font
					(size 1.27 1.27)
				)
			)
		)
		(duplicate_pad_numbers_are_jumpers no)
		(fp_poly
			(pts
				(xy -0.2794 -0.1016) (xy 0.2794 -0.1016) (xy 0.2794 0.9906) (xy -0.2794 0.9906)
			)
			(stroke
				(width 0)
				(type default)
			)
			(fill no)
			(layer "F.CrtYd")
		)
		(fp_line
			(start 0.2794 -0.1016)
			(end -0.2794 -0.1016)
			(stroke
				(width 0.1)
				(type default)
			)
			(layer "F.Fab")
		)
		(fp_line
			(start -0.2794 -0.1016)
			(end -0.2794 0.9906)
			(stroke
				(width 0.1)
				(type default)
			)
			(layer "F.Fab")
		)
		(fp_line
			(start 0.2794 0.9906)
			(end 0.2794 -0.1016)
			(stroke
				(width 0.1)
				(type default)
			)
			(layer "F.Fab")
		)
		(fp_line
			(start -0.2794 0.9906)
			(end 0.2794 0.9906)
			(stroke
				(width 0.1)
				(type default)
			)
			(layer "F.Fab")
		)
		(pad "1" smd rect
			(at 0 0 90)
			(size 0.508 0.508)
			(layers "F.Cu" "F.Mask" "F.Paste")
			(net "PVCCIO_CPU0")
		)
		(pad "2" smd rect
			(at 0 0.889 90)
			(size 0.508 0.508)
			(layers "F.Cu" "F.Mask" "F.Paste")
			(net "GND")
		)
		(zone
			(layer "F.Cu")
			(hatch none 0.5)
			(connect_pads
				(clearance 0)
			)
			(min_thickness 0.25)
			(keepout
				(tracks allowed)
				(vias not_allowed)
				(pads allowed)
				(copperpour not_allowed)
				(footprints allowed)
			)
			(placement
				(enabled no)
				(sheetname "")
			)
			(fill
				(thermal_gap 0.5)
				(thermal_bridge_width 0.5)
				(island_removal_mode 0)
			)
			(polygon
				(pts
					(xy 339.9282 -104.775) (xy 339.9282 -105.283) (xy 340.3092 -105.283) (xy 340.3092 -104.775)
				)
			)
		)
		(zone
			(layer "F.Cu")
			(hatch none 0.5)
			(connect_pads
				(clearance 0)
			)
			(min_thickness 0.25)
			(keepout
				(tracks not_allowed)
				(vias allowed)
				(pads allowed)
				(copperpour not_allowed)
				(footprints allowed)
			)
			(placement
				(enabled no)
				(sheetname "")
			)
			(fill
				(thermal_gap 0.5)
				(thermal_bridge_width 0.5)
				(island_removal_mode 0)
			)
			(polygon
				(pts
					(xy 340.3092 -104.775) (xy 340.3092 -105.283) (xy 339.9282 -105.283) (xy 339.9282 -104.775)
				)
			)
		)
	)
	(footprint ""
		(layer "F.Cu")
		(at 181.991 -32.893 90)
		(property "Reference" "C4F4"
			(at -3.20167 3.429 0)
			(unlocked yes)
			(layer "F.SilkS")
			(effects
				(font
					(size 0.7874 0.5842)
					(thickness 0.1524)
				)
			)
		)
		(property "Value" ""
			(at 0 0 90)
			(layer "F.Fab")
			(effects
				(font
					(size 1.27 1.27)
				)
			)
		)
		(duplicate_pad_numbers_are_jumpers no)
		(fp_line
			(start 2.504948 -1.616456)
			(end 2.504948 1.633728)
			(stroke
				(width 0.1524)
				(type default)
			)
			(layer "F.SilkS")
		)
		(fp_line
			(start 1.6002 -1.616456)
			(end 2.504948 -1.616456)
			(stroke
				(width 0.1524)
				(type default)
			)
			(layer "F.SilkS")
		)
		(fp_line
			(start -1.6002 -1.616456)
			(end -2.563114 -1.616456)
			(stroke
				(width 0.1524)
				(type default)
			)
			(layer "F.SilkS")
		)
		(fp_line
			(start -2.563114 -1.616456)
			(end -2.563114 1.633728)
			(stroke
				(width 0.1524)
				(type default)
			)
			(layer "F.SilkS")
		)
		(fp_line
			(start 2.504948 1.633728)
			(end 1.6002 1.633728)
			(stroke
				(width 0.1524)
				(type default)
			)
			(layer "F.SilkS")
		)
		(fp_line
			(start -2.563114 1.633728)
			(end -1.6002 1.633728)
			(stroke
				(width 0.1524)
				(type default)
			)
			(layer "F.SilkS")
		)
		(fp_line
			(start 2.286 7.366)
			(end 2.286 1.63195)
			(stroke
				(width 0.1524)
				(type default)
			)
			(layer "F.SilkS")
		)
		(fp_line
			(start 2.286 7.366)
			(end 1.600708 7.366)
			(stroke
				(width 0.1524)
				(type default)
			)
			(layer "F.SilkS")
		)
		(fp_line
			(start -2.286 7.366)
			(end -2.286 1.632712)
			(stroke
				(width 0.1524)
				(type default)
			)
			(layer "F.SilkS")
		)
		(fp_line
			(start -2.286 7.366)
			(end -1.60147 7.366)
			(stroke
				(width 0.1524)
				(type default)
			)
			(layer "F.SilkS")
		)
		(fp_rect
			(start -2.286 7.366)
			(end 2.286 -0.254)
			(stroke
				(width 0)
				(type default)
			)
			(fill no)
			(layer "F.CrtYd")
		)
		(fp_line
			(start 2.286 -0.254)
			(end 2.286 7.366)
			(stroke
				(width 0.1)
				(type default)
			)
			(layer "F.Fab")
		)
		(fp_line
			(start -2.286 -0.254)
			(end 2.286 -0.254)
			(stroke
				(width 0.1)
				(type default)
			)
			(layer "F.Fab")
		)
		(fp_line
			(start 2.286 7.366)
			(end -2.286 7.366)
			(stroke
				(width 0.1)
				(type default)
			)
			(layer "F.Fab")
		)
		(fp_line
			(start -2.286 7.366)
			(end -2.286 -0.254)
			(stroke
				(width 0.1)
				(type default)
			)
			(layer "F.Fab")
		)
		(pad "1" smd rect
			(at 0 0 90)
			(size 2.54 3.048)
			(layers "F.Cu" "F.Mask" "F.Paste")
			(net "P12V_STBY")
		)
		(pad "2" smd rect
			(at 0 7.112 90)
			(size 2.54 3.048)
			(layers "F.Cu" "F.Mask" "F.Paste")
			(net "GND")
		)
	)
	(footprint ""
		(layer "F.Cu")
		(at 184.531 -146.685)
		(property "Reference" "C4A12"
			(at 0 0 0)
			(layer "F.SilkS")
			(hide yes)
			(effects
				(font
					(size 1.27 1.27)
				)
			)
		)
		(property "Value" ""
			(at 0 0 0)
			(layer "F.Fab")
			(effects
				(font
					(size 1.27 1.27)
				)
			)
		)
		(duplicate_pad_numbers_are_jumpers no)
		(fp_rect
			(start 0.3048 0.9906)
			(end -0.3048 -0.1016)
			(stroke
				(width 0)
				(type default)
			)
			(fill no)
			(layer "F.CrtYd")
		)
		(fp_line
			(start -0.3048 -0.1016)
			(end -0.3048 0.9906)
			(stroke
				(width 0.1)
				(type default)
			)
			(layer "F.Fab")
		)
		(fp_line
			(start -0.3048 0.9906)
			(end 0.3048 0.9906)
			(stroke
				(width 0.1)
				(type default)
			)
			(layer "F.Fab")
		)
		(fp_line
			(start 0.3048 -0.1016)
			(end -0.3048 -0.1016)
			(stroke
				(width 0.1)
				(type default)
			)
			(layer "F.Fab")
		)
		(fp_line
			(start 0.3048 0.9906)
			(end 0.3048 -0.1016)
			(stroke
				(width 0.1)
				(type default)
			)
			(layer "F.Fab")
		)
		(pad "1" smd rect
			(at 0 0)
			(size 0.508 0.508)
			(layers "F.Cu" "F.Mask" "F.Paste")
			(net "PWRGD_PVTT_DEF_CPU0_R")
		)
		(pad "2" smd rect
			(at 0 0.889)
			(size 0.508 0.508)
			(layers "F.Cu" "F.Mask" "F.Paste")
			(net "GND")
		)
		(zone
			(layer "F.Cu")
			(hatch none 0.5)
			(connect_pads
				(clearance 0)
			)
			(min_thickness 0.25)
			(keepout
				(tracks not_allowed)
				(vias allowed)
				(pads allowed)
				(copperpour not_allowed)
				(footprints allowed)
			)
			(placement
				(enabled no)
				(sheetname "")
			)
			(fill
				(thermal_gap 0.5)
				(thermal_bridge_width 0.5)
				(island_removal_mode 0)
			)
			(polygon
				(pts
					(xy 184.785 -146.05) (xy 184.785 -146.431) (xy 184.277 -146.431) (xy 184.277 -146.05)
				)
			)
		)
		(zone
			(layer "F.Cu")
			(hatch none 0.5)
			(connect_pads
				(clearance 0)
			)
			(min_thickness 0.25)
			(keepout
				(tracks allowed)
				(vias not_allowed)
				(pads allowed)
				(copperpour not_allowed)
				(footprints allowed)
			)
			(placement
				(enabled no)
				(sheetname "")
			)
			(fill
				(thermal_gap 0.5)
				(thermal_bridge_width 0.5)
				(island_removal_mode 0)
			)
			(polygon
				(pts
					(xy 184.785 -146.05) (xy 184.785 -146.431) (xy 184.277 -146.431) (xy 184.277 -146.05)
				)
			)
		)
	)
)
